#ISCELL
  pure_quanta quanta_title_block_c *
  *
#ISCELL
  standard offpage *
  page319_i1
#ISCELL
  standard offpage *
  page319_i11
#ISCELL
  standard offpage *
  page319_i12
#ISCELL
  standard offpage *
  page319_i13
#ISCELL
  standard offpage *
  page319_i14
#ISCELL
  logical_power universal_gnd *
  page319_i15
#ISCELL
  standard offpage *
  page319_i16
#ISCELL
  standard offpage *
  page319_i17
#ISCELL
  standard offpage *
  page319_i18
#ISCELL
  standard offpage *
  page319_i19
#ISCELL
  standard offpage *
  page319_i2
#ISCELL
  standard offpage *
  page319_i20
#ISCELL
  standard offpage *
  page319_i21
#ISCELL
  standard offpage *
  page319_i22
#ISCELL
  standard offpage *
  page319_i23
#ISCELL
  standard offpage *
  page319_i24
#ISCELL
  standard offpage *
  page319_i25
#ISCELL
  standard offpage *
  page319_i26
#ISCELL
  standard offpage *
  page319_i27
#ISCELL
  standard offpage *
  page319_i3
#ISCELL
  standard offpage *
  page319_i30
#ISCELL
  standard offpage *
  page319_i31
#ISCELL
  standard offpage *
  page319_i32
#ISCELL
  standard offpage *
  page319_i33
#ISCELL
  standard offpage *
  page319_i34
#ISCELL
  standard offpage *
  page319_i35
#ISCELL
  standard offpage *
  page319_i36
#ISCELL
  standard offpage *
  page319_i37
#ISCELL
  standard offpage *
  page319_i38
#ISCELL
  standard offpage *
  page319_i39
#ISCELL
  standard offpage *
  page319_i4
#ISCELL
  standard offpage *
  page319_i40
#ISCELL
  standard offpage *
  page319_i41
#ISCELL
  standard offpage *
  page319_i42
#ISCELL
  standard offpage *
  page319_i43
#ISCELL
  standard offpage *
  page319_i44
#ISCELL
  standard offpage *
  page319_i45
#ISCELL
  standard offpage *
  page319_i47
#ISCELL
  standard offpage *
  page319_i49
#ISCELL
  standard offpage *
  page319_i5
#ISCELL
  standard offpage *
  page319_i50
#ISCELL
  standard offpage *
  page319_i51
#ISCELL
  logical_power universal_gnd *
  page319_i52
#CELL
  pure_quanta conn112_10137002101lf *
  page319_i53
#ISCELL
  standard offpage *
  page319_i54
#ISCELL
  standard offpage *
  page319_i55
#ISCELL
  standard offpage *
  page319_i56
#ISCELL
  standard offpage *
  page319_i57
#ISCELL
  standard offpage *
  page319_i58
#ISCELL
  standard offpage *
  page319_i59
#ISCELL
  standard offpage *
  page319_i6
#ISCELL
  standard offpage *
  page319_i60
#ISCELL
  standard offpage *
  page319_i61
#ISCELL
  standard offpage *
  page319_i62
#ISCELL
  standard offpage *
  page319_i63
#ISCELL
  standard offpage *
  page319_i64
#ISCELL
  standard offpage *
  page319_i65
#ISCELL
  standard offpage *
  page319_i68
#ISCELL
  standard offpage *
  page319_i69
#ISCELL
  standard offpage *
  page319_i7
#ISCELL
  standard offpage *
  page319_i70
#ISCELL
  standard offpage *
  page319_i71
#ISCELL
  standard offpage *
  page319_i72
#ISCELL
  standard offpage *
  page319_i73
#ISCELL
  standard offpage *
  page319_i74
#ISCELL
  standard offpage *
  page319_i75
#CELL
  pure_quanta conn112_10137002101lf *
  page319_i76
#ISCELL
  standard offpage *
  page319_i8
#ISCELL
  standard offpage *
  page319_i83
#ISCELL
  standard offpage *
  page319_i84
#ISCELL
  standard offpage *
  page319_i85
#ISCELL
  standard offpage *
  page319_i86
#ISCELL
  standard offpage *
  page319_i87
#ISCELL
  standard offpage *
  page319_i88
#ISCELL
  standard offpage *
  page319_i89
#ISCELL
  standard offpage *
  page319_i90
